G04 ================== begin FILE IDENTIFICATION RECORD ==================*
G04 Layout Name:  15968-1a.brd*
G04 Film Name:    TSMD*
G04 File Format:  Gerber RS274X*
G04 File Origin:  Cadence Allegro 16.5-S058*
G04 Origin Date:  Fri Oct 14 10:23:32 2016*
G04 *
G04 Layer:  VIA CLASS/PASTEMASK_TOP*
G04 Layer:  PIN/PASTEMASK_TOP*
G04 Layer:  PACKAGE GEOMETRY/PASTEMASK_TOP*
G04 Layer:  DRAWING FORMAT/LAYER_PCB_STORY*
G04 Layer:  DRAWING FORMAT/LAYER_PAST_T*
G04 Layer:  BOARD GEOMETRY/PANEL_OUTLINE*
G04 *
G04 Offset:    (0.00 0.00)*
G04 Mirror:    No*
G04 Mode:      Positive*
G04 Rotation:  0*
G04 FullContactRelief:  No*
G04 UndefLineWidth:     6.00*
G04 ================== end FILE IDENTIFICATION RECORD ====================*
%FSLAX35Y35*MOIN*%
%IR0*IPPOS*OFA0.00000B0.00000*MIA0B0*SFA1.00000B1.00000*%
%AMMACRO51*
4,1,40,.013,.017,
-.013,.017,
-.013695,.016939,
-.014368,.016759,
-.015,.016464,
-.015571,.016064,
-.016064,.015571,
-.016464,.015,
-.016759,.014368,
-.016939,.013695,
-.017,.013,
-.017,-.013,
-.016939,-.013695,
-.016759,-.014368,
-.016464,-.015,
-.016064,-.015571,
-.015571,-.016064,
-.015,-.016464,
-.014368,-.016759,
-.013695,-.016939,
-.013,-.017,
.013,-.017,
.013695,-.016939,
.014368,-.016759,
.015,-.016464,
.015571,-.016064,
.016064,-.015571,
.016464,-.015,
.016759,-.014368,
.016939,-.013695,
.017,-.013,
.017,.013,
.016939,.013695,
.016759,.014368,
.016464,.015,
.016064,.015571,
.015571,.016064,
.015,.016464,
.014368,.016759,
.013695,.016939,
.013,.017,
0.0*
%
%ADD51MACRO51*%
%AMMACRO18*
4,1,40,.017,-.013,
.017,.013,
.016939,.013695,
.016759,.014368,
.016464,.015,
.016064,.015571,
.015571,.016064,
.015,.016464,
.014368,.016759,
.013695,.016939,
.013,.017,
-.013,.017,
-.013695,.016939,
-.014368,.016759,
-.015,.016464,
-.015571,.016064,
-.016064,.015571,
-.016464,.015,
-.016759,.014368,
-.016939,.013695,
-.017,.013,
-.017,-.013,
-.016939,-.013695,
-.016759,-.014368,
-.016464,-.015,
-.016064,-.015571,
-.015571,-.016064,
-.015,-.016464,
-.014368,-.016759,
-.013695,-.016939,
-.013,-.017,
.013,-.017,
.013695,-.016939,
.014368,-.016759,
.015,-.016464,
.015571,-.016064,
.016064,-.015571,
.016464,-.015,
.016759,-.014368,
.016939,-.013695,
.017,-.013,
0.0*
%
%ADD18MACRO18*%
%ADD13R,.141X.061*%
%ADD37R,.061X.141*%
%AMMACRO21*
21,1,.065,.05,0.0,0.0,135.*%
%ADD21MACRO21*%
%ADD44C,.04*%
%ADD58C,.024*%
%ADD11C,.028*%
%ADD12C,.086*%
%AMMACRO41*
4,1,40,.007,.011,
-.007,.011,
-.007695,.010939,
-.008368,.010759,
-.009,.010464,
-.009571,.010064,
-.010064,.009571,
-.010464,.009,
-.010759,.008368,
-.010939,.007695,
-.011,.007,
-.011,-.007,
-.010939,-.007695,
-.010759,-.008368,
-.010464,-.009,
-.010064,-.009571,
-.009571,-.010064,
-.009,-.010464,
-.008368,-.010759,
-.007695,-.010939,
-.007,-.011,
.007,-.011,
.007695,-.010939,
.008368,-.010759,
.009,-.010464,
.009571,-.010064,
.010064,-.009571,
.010464,-.009,
.010759,-.008368,
.010939,-.007695,
.011,-.007,
.011,.007,
.010939,.007695,
.010759,.008368,
.010464,.009,
.010064,.009571,
.009571,.010064,
.009,.010464,
.008368,.010759,
.007695,.010939,
.007,.011,
0.0*
%
%ADD41MACRO41*%
%ADD36R,.065X.065*%
%AMMACRO30*
4,1,40,.011,-.007,
.011,.007,
.010939,.007695,
.010759,.008368,
.010464,.009,
.010064,.009571,
.009571,.010064,
.009,.010464,
.008368,.010759,
.007695,.010939,
.007,.011,
-.007,.011,
-.007695,.010939,
-.008368,.010759,
-.009,.010464,
-.009571,.010064,
-.010064,.009571,
-.010464,.009,
-.010759,.008368,
-.010939,.007695,
-.011,.007,
-.011,-.007,
-.010939,-.007695,
-.010759,-.008368,
-.010464,-.009,
-.010064,-.009571,
-.009571,-.010064,
-.009,-.010464,
-.008368,-.010759,
-.007695,-.010939,
-.007,-.011,
.007,-.011,
.007695,-.010939,
.008368,-.010759,
.009,-.010464,
.009571,-.010064,
.010064,-.009571,
.010464,-.009,
.010759,-.008368,
.010939,-.007695,
.011,-.007,
0.0*
%
%ADD30MACRO30*%
%AMMACRO47*
4,1,40,-.012,.008,
-.012,-.008,
-.011939,-.008695,
-.011759,-.009368,
-.011464,-.01,
-.011064,-.010571,
-.010571,-.011064,
-.01,-.011464,
-.009368,-.011759,
-.008695,-.011939,
-.008,-.012,
.008,-.012,
.008695,-.011939,
.009368,-.011759,
.01,-.011464,
.010571,-.011064,
.011064,-.010571,
.011464,-.01,
.011759,-.009368,
.011939,-.008695,
.012,-.008,
.012,.008,
.011939,.008695,
.011759,.009368,
.011464,.01,
.011064,.010571,
.010571,.011064,
.01,.011464,
.009368,.011759,
.008695,.011939,
.008,.012,
-.008,.012,
-.008695,.011939,
-.009368,.011759,
-.01,.011464,
-.010571,.011064,
-.011064,.010571,
-.011464,.01,
-.011759,.009368,
-.011939,.008695,
-.012,.008,
0.0*
%
%ADD47MACRO47*%
%AMMACRO23*
4,1,40,.008,.012,
-.008,.012,
-.008695,.011939,
-.009368,.011759,
-.01,.011464,
-.010571,.011064,
-.011064,.010571,
-.011464,.01,
-.011759,.009368,
-.011939,.008695,
-.012,.008,
-.012,-.008,
-.011939,-.008695,
-.011759,-.009368,
-.011464,-.01,
-.011064,-.010571,
-.010571,-.011064,
-.01,-.011464,
-.009368,-.011759,
-.008695,-.011939,
-.008,-.012,
.008,-.012,
.008695,-.011939,
.009368,-.011759,
.01,-.011464,
.010571,-.011064,
.011064,-.010571,
.011464,-.01,
.011759,-.009368,
.011939,-.008695,
.012,-.008,
.012,.008,
.011939,.008695,
.011759,.009368,
.011464,.01,
.011064,.010571,
.010571,.011064,
.01,.011464,
.009368,.011759,
.008695,.011939,
.008,.012,
0.0*
%
%ADD23MACRO23*%
%AMMACRO60*
4,1,40,-.013,-.017,
.013,-.017,
.013695,-.016939,
.014368,-.016759,
.015,-.016464,
.015571,-.016064,
.016064,-.015571,
.016464,-.015,
.016759,-.014368,
.016939,-.013695,
.017,-.013,
.017,.013,
.016939,.013695,
.016759,.014368,
.016464,.015,
.016064,.015571,
.015571,.016064,
.015,.016464,
.014368,.016759,
.013695,.016939,
.013,.017,
-.013,.017,
-.013695,.016939,
-.014368,.016759,
-.015,.016464,
-.015571,.016064,
-.016064,.015571,
-.016464,.015,
-.016759,.014368,
-.016939,.013695,
-.017,.013,
-.017,-.013,
-.016939,-.013695,
-.016759,-.014368,
-.016464,-.015,
-.016064,-.015571,
-.015571,-.016064,
-.015,-.016464,
-.014368,-.016759,
-.013695,-.016939,
-.013,-.017,
0.0*
%
%ADD60MACRO60*%
%AMMACRO39*
4,1,40,-.017,.013,
-.017,-.013,
-.016939,-.013695,
-.016759,-.014368,
-.016464,-.015,
-.016064,-.015571,
-.015571,-.016064,
-.015,-.016464,
-.014368,-.016759,
-.013695,-.016939,
-.013,-.017,
.013,-.017,
.013695,-.016939,
.014368,-.016759,
.015,-.016464,
.015571,-.016064,
.016064,-.015571,
.016464,-.015,
.016759,-.014368,
.016939,-.013695,
.017,-.013,
.017,.013,
.016939,.013695,
.016759,.014368,
.016464,.015,
.016064,.015571,
.015571,.016064,
.015,.016464,
.014368,.016759,
.013695,.016939,
.013,.017,
-.013,.017,
-.013695,.016939,
-.014368,.016759,
-.015,.016464,
-.015571,.016064,
-.016064,.015571,
-.016464,.015,
-.016759,.014368,
-.016939,.013695,
-.017,.013,
0.0*
%
%ADD39MACRO39*%
%AMMACRO42*
4,1,40,.007,.011,
-.007,.011,
-.007695,.010939,
-.008368,.010759,
-.009,.010464,
-.009571,.010064,
-.010064,.009571,
-.010464,.009,
-.010759,.008368,
-.010939,.007695,
-.011,.007,
-.011,-.007,
-.010939,-.007695,
-.010759,-.008368,
-.010464,-.009,
-.010064,-.009571,
-.009571,-.010064,
-.009,-.010464,
-.008368,-.010759,
-.007695,-.010939,
-.007,-.011,
.007,-.011,
.007695,-.010939,
.008368,-.010759,
.009,-.010464,
.009571,-.010064,
.010064,-.009571,
.010464,-.009,
.010759,-.008368,
.010939,-.007695,
.011,-.007,
.011,.007,
.010939,.007695,
.010759,.008368,
.010464,.009,
.010064,.009571,
.009571,.010064,
.009,.010464,
.008368,.010759,
.007695,.010939,
.007,.011,
0.0*
%
%ADD42MACRO42*%
%AMMACRO31*
4,1,40,.011,-.007,
.011,.007,
.010939,.007695,
.010759,.008368,
.010464,.009,
.010064,.009571,
.009571,.010064,
.009,.010464,
.008368,.010759,
.007695,.010939,
.007,.011,
-.007,.011,
-.007695,.010939,
-.008368,.010759,
-.009,.010464,
-.009571,.010064,
-.010064,.009571,
-.010464,.009,
-.010759,.008368,
-.010939,.007695,
-.011,.007,
-.011,-.007,
-.010939,-.007695,
-.010759,-.008368,
-.010464,-.009,
-.010064,-.009571,
-.009571,-.010064,
-.009,-.010464,
-.008368,-.010759,
-.007695,-.010939,
-.007,-.011,
.007,-.011,
.007695,-.010939,
.008368,-.010759,
.009,-.010464,
.009571,-.010064,
.010064,-.009571,
.010464,-.009,
.010759,-.008368,
.010939,-.007695,
.011,-.007,
0.0*
%
%ADD31MACRO31*%
%AMMACRO46*
4,1,40,-.012,.008,
-.012,-.008,
-.011939,-.008695,
-.011759,-.009368,
-.011464,-.01,
-.011064,-.010571,
-.010571,-.011064,
-.01,-.011464,
-.009368,-.011759,
-.008695,-.011939,
-.008,-.012,
.008,-.012,
.008695,-.011939,
.009368,-.011759,
.01,-.011464,
.010571,-.011064,
.011064,-.010571,
.011464,-.01,
.011759,-.009368,
.011939,-.008695,
.012,-.008,
.012,.008,
.011939,.008695,
.011759,.009368,
.011464,.01,
.011064,.010571,
.010571,.011064,
.01,.011464,
.009368,.011759,
.008695,.011939,
.008,.012,
-.008,.012,
-.008695,.011939,
-.009368,.011759,
-.01,.011464,
-.010571,.011064,
-.011064,.010571,
-.011464,.01,
-.011759,.009368,
-.011939,.008695,
-.012,.008,
0.0*
%
%ADD46MACRO46*%
%AMMACRO22*
4,1,40,.008,.012,
-.008,.012,
-.008695,.011939,
-.009368,.011759,
-.01,.011464,
-.010571,.011064,
-.011064,.010571,
-.011464,.01,
-.011759,.009368,
-.011939,.008695,
-.012,.008,
-.012,-.008,
-.011939,-.008695,
-.011759,-.009368,
-.011464,-.01,
-.011064,-.010571,
-.010571,-.011064,
-.01,-.011464,
-.009368,-.011759,
-.008695,-.011939,
-.008,-.012,
.008,-.012,
.008695,-.011939,
.009368,-.011759,
.01,-.011464,
.010571,-.011064,
.011064,-.010571,
.011464,-.01,
.011759,-.009368,
.011939,-.008695,
.012,-.008,
.012,.008,
.011939,.008695,
.011759,.009368,
.011464,.01,
.011064,.010571,
.010571,.011064,
.01,.011464,
.009368,.011759,
.008695,.011939,
.008,.012,
0.0*
%
%ADD22MACRO22*%
%AMMACRO59*
4,1,40,-.013,-.017,
.013,-.017,
.013695,-.016939,
.014368,-.016759,
.015,-.016464,
.015571,-.016064,
.016064,-.015571,
.016464,-.015,
.016759,-.014368,
.016939,-.013695,
.017,-.013,
.017,.013,
.016939,.013695,
.016759,.014368,
.016464,.015,
.016064,.015571,
.015571,.016064,
.015,.016464,
.014368,.016759,
.013695,.016939,
.013,.017,
-.013,.017,
-.013695,.016939,
-.014368,.016759,
-.015,.016464,
-.015571,.016064,
-.016064,.015571,
-.016464,.015,
-.016759,.014368,
-.016939,.013695,
-.017,.013,
-.017,-.013,
-.016939,-.013695,
-.016759,-.014368,
-.016464,-.015,
-.016064,-.015571,
-.015571,-.016064,
-.015,-.016464,
-.014368,-.016759,
-.013695,-.016939,
-.013,-.017,
0.0*
%
%ADD59MACRO59*%
%AMMACRO40*
4,1,40,-.017,.013,
-.017,-.013,
-.016939,-.013695,
-.016759,-.014368,
-.016464,-.015,
-.016064,-.015571,
-.015571,-.016064,
-.015,-.016464,
-.014368,-.016759,
-.013695,-.016939,
-.013,-.017,
.013,-.017,
.013695,-.016939,
.014368,-.016759,
.015,-.016464,
.015571,-.016064,
.016064,-.015571,
.016464,-.015,
.016759,-.014368,
.016939,-.013695,
.017,-.013,
.017,.013,
.016939,.013695,
.016759,.014368,
.016464,.015,
.016064,.015571,
.015571,.016064,
.015,.016464,
.014368,.016759,
.013695,.016939,
.013,.017,
-.013,.017,
-.013695,.016939,
-.014368,.016759,
-.015,.016464,
-.015571,.016064,
-.016064,.015571,
-.016464,.015,
-.016759,.014368,
-.016939,.013695,
-.017,.013,
0.0*
%
%ADD40MACRO40*%
%ADD56R,.012X.052*%
%ADD55R,.052X.012*%
%ADD52R,.06X.014*%
%ADD45R,.016X.04*%
%ADD43R,.014X.06*%
%ADD35R,.036X.012*%
%ADD34R,.012X.036*%
%ADD63R,.012X.036*%
%ADD62R,.036X.012*%
%ADD54R,.046X.012*%
%ADD53R,.012X.046*%
%ADD38R,.05X.065*%
%ADD61R,.055X.042*%
%ADD16R,.065X.05*%
%ADD10R,.045X.055*%
%ADD64R,.055X.045*%
%ADD49R,.016X.048*%
%ADD57R,.146X.146*%
%AMMACRO48*
4,1,40,.024,.012,
.024,-.012,
.023878,-.013389,
.023518,-.014736,
.022928,-.016,
.022128,-.017142,
.021142,-.018128,
.02,-.018928,
.018736,-.019518,
.017389,-.019878,
.016,-.02,
-.016,-.02,
-.017389,-.019878,
-.018736,-.019518,
-.02,-.018928,
-.021142,-.018128,
-.022128,-.017142,
-.022928,-.016,
-.023518,-.014736,
-.023878,-.013389,
-.024,-.012,
-.024,.012,
-.023878,.013389,
-.023518,.014736,
-.022928,.016,
-.022128,.017142,
-.021142,.018128,
-.02,.018928,
-.018736,.019518,
-.017389,.019878,
-.016,.02,
.016,.02,
.017389,.019878,
.018736,.019518,
.02,.018928,
.021142,.018128,
.022128,.017142,
.022928,.016,
.023518,.014736,
.023878,.013389,
.024,.012,
0.0*
%
%ADD48MACRO48*%
%AMMACRO32*
4,1,40,-.007,-.011,
.007,-.011,
.007695,-.010939,
.008368,-.010759,
.009,-.010464,
.009571,-.010064,
.010064,-.009571,
.010464,-.009,
.010759,-.008368,
.010939,-.007695,
.011,-.007,
.011,.007,
.010939,.007695,
.010759,.008368,
.010464,.009,
.010064,.009571,
.009571,.010064,
.009,.010464,
.008368,.010759,
.007695,.010939,
.007,.011,
-.007,.011,
-.007695,.010939,
-.008368,.010759,
-.009,.010464,
-.009571,.010064,
-.010064,.009571,
-.010464,.009,
-.010759,.008368,
-.010939,.007695,
-.011,.007,
-.011,-.007,
-.010939,-.007695,
-.010759,-.008368,
-.010464,-.009,
-.010064,-.009571,
-.009571,-.010064,
-.009,-.010464,
-.008368,-.010759,
-.007695,-.010939,
-.007,-.011,
0.0*
%
%ADD32MACRO32*%
%AMMACRO29*
4,1,40,.012,-.008,
.012,.008,
.011939,.008695,
.011759,.009368,
.011464,.01,
.011064,.010571,
.010571,.011064,
.01,.011464,
.009368,.011759,
.008695,.011939,
.008,.012,
-.008,.012,
-.008695,.011939,
-.009368,.011759,
-.01,.011464,
-.010571,.011064,
-.011064,.010571,
-.011464,.01,
-.011759,.009368,
-.011939,.008695,
-.012,.008,
-.012,-.008,
-.011939,-.008695,
-.011759,-.009368,
-.011464,-.01,
-.011064,-.010571,
-.010571,-.011064,
-.01,-.011464,
-.009368,-.011759,
-.008695,-.011939,
-.008,-.012,
.008,-.012,
.008695,-.011939,
.009368,-.011759,
.01,-.011464,
.010571,-.011064,
.011064,-.010571,
.011464,-.01,
.011759,-.009368,
.011939,-.008695,
.012,-.008,
0.0*
%
%ADD29MACRO29*%
%AMMACRO27*
4,1,40,-.008,-.012,
.008,-.012,
.008695,-.011939,
.009368,-.011759,
.01,-.011464,
.010571,-.011064,
.011064,-.010571,
.011464,-.01,
.011759,-.009368,
.011939,-.008695,
.012,-.008,
.012,.008,
.011939,.008695,
.011759,.009368,
.011464,.01,
.011064,.010571,
.010571,.011064,
.01,.011464,
.009368,.011759,
.008695,.011939,
.008,.012,
-.008,.012,
-.008695,.011939,
-.009368,.011759,
-.01,.011464,
-.010571,.011064,
-.011064,.010571,
-.011464,.01,
-.011759,.009368,
-.011939,.008695,
-.012,.008,
-.012,-.008,
-.011939,-.008695,
-.011759,-.009368,
-.011464,-.01,
-.011064,-.010571,
-.010571,-.011064,
-.01,-.011464,
-.009368,-.011759,
-.008695,-.011939,
-.008,-.012,
0.0*
%
%ADD27MACRO27*%
%AMMACRO25*
4,1,44,-.01414,-.00283,
-.00283,-.01414,
-.002296,-.014589,
-.001693,-.014938,
-.001038,-.015177,
-.000351,-.015298,
.000346,-.015299,
.001033,-.015178,
.001688,-.01494,
.002292,-.014592,
.002827,-.014144,
.00283,-.01414,
.01414,-.00283,
.014589,-.002296,
.014938,-.001693,
.015177,-.001038,
.015298,-.000351,
.015299,.000346,
.015178,.001033,
.01494,.001688,
.014592,.002292,
.014144,.002827,
.01414,.00283,
.00283,.01414,
.002296,.014589,
.001693,.014938,
.001038,.015177,
.000351,.015298,
-.000346,.015299,
-.001033,.015178,
-.001688,.01494,
-.002292,.014592,
-.002827,.014144,
-.00283,.01414,
-.01414,.00283,
-.014589,.002296,
-.014938,.001693,
-.015177,.001038,
-.015298,.000351,
-.015299,-.000346,
-.015178,-.001033,
-.01494,-.001688,
-.014592,-.002292,
-.014144,-.002827,
-.01414,-.00283,
0.0*
%
%ADD25MACRO25*%
%AMMACRO19*
4,1,40,-.01273,-.00283,
-.00283,-.01273,
-.002294,-.013176,
-.00169,-.013525,
-.001035,-.013763,
-.000348,-.013884,
.000349,-.013884,
.001036,-.013763,
.001691,-.013525,
.002295,-.013176,
.00283,-.01273,
.01273,-.00283,
.013176,-.002294,
.013525,-.00169,
.013763,-.001035,
.013884,-.000348,
.013884,.000349,
.013763,.001036,
.013525,.001691,
.013176,.002295,
.01273,.00283,
.00283,.01273,
.002294,.013176,
.00169,.013525,
.001035,.013763,
.000348,.013884,
-.000349,.013884,
-.001036,.013763,
-.001691,.013525,
-.002295,.013176,
-.00283,.01273,
-.01273,.00283,
-.013176,.002294,
-.013525,.00169,
-.013763,.001035,
-.013884,.000348,
-.013884,-.000349,
-.013763,-.001036,
-.013525,-.001691,
-.013176,-.002295,
-.01273,-.00283,
0.0*
%
%ADD19MACRO19*%
%AMMACRO14*
4,1,40,-.011,.007,
-.011,-.007,
-.010939,-.007695,
-.010759,-.008368,
-.010464,-.009,
-.010064,-.009571,
-.009571,-.010064,
-.009,-.010464,
-.008368,-.010759,
-.007695,-.010939,
-.007,-.011,
.007,-.011,
.007695,-.010939,
.008368,-.010759,
.009,-.010464,
.009571,-.010064,
.010064,-.009571,
.010464,-.009,
.010759,-.008368,
.010939,-.007695,
.011,-.007,
.011,.007,
.010939,.007695,
.010759,.008368,
.010464,.009,
.010064,.009571,
.009571,.010064,
.009,.010464,
.008368,.010759,
.007695,.010939,
.007,.011,
-.007,.011,
-.007695,.010939,
-.008368,.010759,
-.009,.010464,
-.009571,.010064,
-.010064,.009571,
-.010464,.009,
-.010759,.008368,
-.010939,.007695,
-.011,.007,
0.0*
%
%ADD14MACRO14*%
%AMMACRO50*
4,1,40,.013,.017,
-.013,.017,
-.013695,.016939,
-.014368,.016759,
-.015,.016464,
-.015571,.016064,
-.016064,.015571,
-.016464,.015,
-.016759,.014368,
-.016939,.013695,
-.017,.013,
-.017,-.013,
-.016939,-.013695,
-.016759,-.014368,
-.016464,-.015,
-.016064,-.015571,
-.015571,-.016064,
-.015,-.016464,
-.014368,-.016759,
-.013695,-.016939,
-.013,-.017,
.013,-.017,
.013695,-.016939,
.014368,-.016759,
.015,-.016464,
.015571,-.016064,
.016064,-.015571,
.016464,-.015,
.016759,-.014368,
.016939,-.013695,
.017,-.013,
.017,.013,
.016939,.013695,
.016759,.014368,
.016464,.015,
.016064,.015571,
.015571,.016064,
.015,.016464,
.014368,.016759,
.013695,.016939,
.013,.017,
0.0*
%
%ADD50MACRO50*%
%AMMACRO17*
4,1,40,.017,-.013,
.017,.013,
.016939,.013695,
.016759,.014368,
.016464,.015,
.016064,.015571,
.015571,.016064,
.015,.016464,
.014368,.016759,
.013695,.016939,
.013,.017,
-.013,.017,
-.013695,.016939,
-.014368,.016759,
-.015,.016464,
-.015571,.016064,
-.016064,.015571,
-.016464,.015,
-.016759,.014368,
-.016939,.013695,
-.017,.013,
-.017,-.013,
-.016939,-.013695,
-.016759,-.014368,
-.016464,-.015,
-.016064,-.015571,
-.015571,-.016064,
-.015,-.016464,
-.014368,-.016759,
-.013695,-.016939,
-.013,-.017,
.013,-.017,
.013695,-.016939,
.014368,-.016759,
.015,-.016464,
.015571,-.016064,
.016064,-.015571,
.016464,-.015,
.016759,-.014368,
.016939,-.013695,
.017,-.013,
0.0*
%
%ADD17MACRO17*%
%AMMACRO33*
4,1,40,-.007,-.011,
.007,-.011,
.007695,-.010939,
.008368,-.010759,
.009,-.010464,
.009571,-.010064,
.010064,-.009571,
.010464,-.009,
.010759,-.008368,
.010939,-.007695,
.011,-.007,
.011,.007,
.010939,.007695,
.010759,.008368,
.010464,.009,
.010064,.009571,
.009571,.010064,
.009,.010464,
.008368,.010759,
.007695,.010939,
.007,.011,
-.007,.011,
-.007695,.010939,
-.008368,.010759,
-.009,.010464,
-.009571,.010064,
-.010064,.009571,
-.010464,.009,
-.010759,.008368,
-.010939,.007695,
-.011,.007,
-.011,-.007,
-.010939,-.007695,
-.010759,-.008368,
-.010464,-.009,
-.010064,-.009571,
-.009571,-.010064,
-.009,-.010464,
-.008368,-.010759,
-.007695,-.010939,
-.007,-.011,
0.0*
%
%ADD33MACRO33*%
%AMMACRO28*
4,1,40,.012,-.008,
.012,.008,
.011939,.008695,
.011759,.009368,
.011464,.01,
.011064,.010571,
.010571,.011064,
.01,.011464,
.009368,.011759,
.008695,.011939,
.008,.012,
-.008,.012,
-.008695,.011939,
-.009368,.011759,
-.01,.011464,
-.010571,.011064,
-.011064,.010571,
-.011464,.01,
-.011759,.009368,
-.011939,.008695,
-.012,.008,
-.012,-.008,
-.011939,-.008695,
-.011759,-.009368,
-.011464,-.01,
-.011064,-.010571,
-.010571,-.011064,
-.01,-.011464,
-.009368,-.011759,
-.008695,-.011939,
-.008,-.012,
.008,-.012,
.008695,-.011939,
.009368,-.011759,
.01,-.011464,
.010571,-.011064,
.011064,-.010571,
.011464,-.01,
.011759,-.009368,
.011939,-.008695,
.012,-.008,
0.0*
%
%ADD28MACRO28*%
%AMMACRO26*
4,1,40,-.008,-.012,
.008,-.012,
.008695,-.011939,
.009368,-.011759,
.01,-.011464,
.010571,-.011064,
.011064,-.010571,
.011464,-.01,
.011759,-.009368,
.011939,-.008695,
.012,-.008,
.012,.008,
.011939,.008695,
.011759,.009368,
.011464,.01,
.011064,.010571,
.010571,.011064,
.01,.011464,
.009368,.011759,
.008695,.011939,
.008,.012,
-.008,.012,
-.008695,.011939,
-.009368,.011759,
-.01,.011464,
-.010571,.011064,
-.011064,.010571,
-.011464,.01,
-.011759,.009368,
-.011939,.008695,
-.012,.008,
-.012,-.008,
-.011939,-.008695,
-.011759,-.009368,
-.011464,-.01,
-.011064,-.010571,
-.010571,-.011064,
-.01,-.011464,
-.009368,-.011759,
-.008695,-.011939,
-.008,-.012,
0.0*
%
%ADD26MACRO26*%
%AMMACRO24*
4,1,44,-.01414,-.00283,
-.00283,-.01414,
-.002296,-.014589,
-.001693,-.014938,
-.001038,-.015177,
-.000351,-.015298,
.000346,-.015299,
.001033,-.015178,
.001688,-.01494,
.002292,-.014592,
.002827,-.014144,
.00283,-.01414,
.01414,-.00283,
.014589,-.002296,
.014938,-.001693,
.015177,-.001038,
.015298,-.000351,
.015299,.000346,
.015178,.001033,
.01494,.001688,
.014592,.002292,
.014144,.002827,
.01414,.00283,
.00283,.01414,
.002296,.014589,
.001693,.014938,
.001038,.015177,
.000351,.015298,
-.000346,.015299,
-.001033,.015178,
-.001688,.01494,
-.002292,.014592,
-.002827,.014144,
-.00283,.01414,
-.01414,.00283,
-.014589,.002296,
-.014938,.001693,
-.015177,.001038,
-.015298,.000351,
-.015299,-.000346,
-.015178,-.001033,
-.01494,-.001688,
-.014592,-.002292,
-.014144,-.002827,
-.01414,-.00283,
0.0*
%
%ADD24MACRO24*%
%AMMACRO20*
4,1,40,-.01273,-.00283,
-.00283,-.01273,
-.002294,-.013176,
-.00169,-.013525,
-.001035,-.013763,
-.000348,-.013884,
.000349,-.013884,
.001036,-.013763,
.001691,-.013525,
.002295,-.013176,
.00283,-.01273,
.01273,-.00283,
.013176,-.002294,
.013525,-.00169,
.013763,-.001035,
.013884,-.000348,
.013884,.000349,
.013763,.001036,
.013525,.001691,
.013176,.002295,
.01273,.00283,
.00283,.01273,
.002294,.013176,
.00169,.013525,
.001035,.013763,
.000348,.013884,
-.000349,.013884,
-.001036,.013763,
-.001691,.013525,
-.002295,.013176,
-.00283,.01273,
-.01273,.00283,
-.013176,.002294,
-.013525,.00169,
-.013763,.001035,
-.013884,.000348,
-.013884,-.000349,
-.013763,-.001036,
-.013525,-.001691,
-.013176,-.002295,
-.01273,-.00283,
0.0*
%
%ADD20MACRO20*%
%AMMACRO15*
4,1,40,-.011,.007,
-.011,-.007,
-.010939,-.007695,
-.010759,-.008368,
-.010464,-.009,
-.010064,-.009571,
-.009571,-.010064,
-.009,-.010464,
-.008368,-.010759,
-.007695,-.010939,
-.007,-.011,
.007,-.011,
.007695,-.010939,
.008368,-.010759,
.009,-.010464,
.009571,-.010064,
.010064,-.009571,
.010464,-.009,
.010759,-.008368,
.010939,-.007695,
.011,-.007,
.011,.007,
.010939,.007695,
.010759,.008368,
.010464,.009,
.010064,.009571,
.009571,.010064,
.009,.010464,
.008368,.010759,
.007695,.010939,
.007,.011,
-.007,.011,
-.007695,.010939,
-.008368,.010759,
-.009,.010464,
-.009571,.010064,
-.010064,.009571,
-.010464,.009,
-.010759,.008368,
-.010939,.007695,
-.011,.007,
0.0*
%
%ADD15MACRO15*%
%ADD65C,.02*%
%ADD66C,.005*%
%ADD67C,.006*%
G75*
%LPD*%
G75*
G54D10*
X28000Y75500D03*
X63100Y82000D03*
X70700D03*
X35600Y75500D03*
X103000Y196800D03*
X110600D03*
G54D20*
X45526Y94769D03*
X48409Y97652D03*
X46287Y151799D03*
X49131Y154709D03*
G54D11*
X12100Y180900D03*
X28000Y216500D03*
X102800Y61700D03*
X92400Y85300D03*
X89100Y81000D03*
X50900Y166800D03*
X57400Y146000D03*
X54600Y140600D03*
X90972Y139034D03*
X91004Y134234D03*
X89700Y152300D03*
X93700Y149200D03*
X63400Y168300D03*
X62500Y161700D03*
X76613Y167516D03*
X88400Y158500D03*
X89500Y167700D03*
X70800Y152000D03*
X93200Y156000D03*
X87309Y163428D03*
X92100Y143700D03*
X74100Y221900D03*
X84400Y202800D03*
X89944Y202832D03*
X94900Y198600D03*
X60400Y187700D03*
X68200Y203200D03*
X63300Y203000D03*
X122500Y-6600D03*
X151800Y13100D03*
X142000Y-30200D03*
X110300Y36000D03*
X108600Y73000D03*
X117500Y79148D03*
X120000Y48500D03*
X152500Y67800D03*
X117400Y85048D03*
X109900Y53000D03*
X181800Y110500D03*
X116400Y103800D03*
X186688Y183400D03*
X185788Y188700D03*
X199500Y98100D03*
X251700Y171900D03*
X242100Y171200D03*
X250400Y189100D03*
X211888Y189000D03*
X335100Y31400D03*
X334700Y24369D03*
X339900Y35700D03*
X338100Y65400D03*
X334200Y47700D03*
X342900Y73200D03*
X289000Y176600D03*
X289600Y171800D03*
X319700Y178200D03*
X314000Y178400D03*
X292581Y179869D03*
X309500Y190300D03*
X321700Y190100D03*
X368700Y-1531D03*
X369900Y7300D03*
X391100Y4500D03*
X369700Y12700D03*
X369482Y17496D03*
X396000Y5000D03*
X419450Y16771D03*
X409550Y18971D03*
X411450Y-8329D03*
X408800Y55500D03*
X416500Y76200D03*
X409700Y77200D03*
X422556Y94629D03*
X369900Y23369D03*
X387800Y29800D03*
X380700Y74400D03*
X373000Y44900D03*
X372900Y50000D03*
X393768Y48100D03*
X373100Y55600D03*
X393900Y57900D03*
X389800Y73500D03*
X374800Y29516D03*
X375500Y74100D03*
X370351Y31320D03*
X370800Y72800D03*
X434525Y37420D03*
X444697Y41899D03*
X445185Y62776D03*
X448264Y70300D03*
X445063Y57977D03*
X463919Y56185D03*
X443396Y23617D03*
X444800Y37100D03*
X439800D03*
X508300Y229900D03*
X476797Y222299D03*
X524445Y71497D03*
X522293Y169769D03*
X515100Y169500D03*
X534700Y173200D03*
X537600Y169100D03*
X528800Y170000D03*
X509600Y220100D03*
X517100Y194600D03*
X509300Y198400D03*
G54D30*
X98700Y60700D03*
X95700Y179800D03*
Y164800D03*
X59300Y157700D03*
X106178Y226617D03*
X63400Y210400D03*
X67400D03*
X71500D03*
X83500D03*
X95900D03*
X55900D03*
X108800Y49100D03*
X116671Y111165D03*
X120998Y111171D03*
X181152Y170042D03*
X185182D03*
X234200Y171400D03*
X301100Y174800D03*
X307000Y178100D03*
X411450Y2402D03*
X400200Y4500D03*
X413800Y22700D03*
X395130Y81602D03*
X399360D03*
X443445Y33007D03*
X450400Y40500D03*
X435287Y33008D03*
X436700Y116000D03*
X526110Y165902D03*
X517530Y165802D03*
G54D12*
X14794Y226306D03*
X542107Y17432D03*
X585785Y228866D03*
G54D21*
X39711Y97911D03*
X47489Y105689D03*
X38232Y154310D03*
X46010Y162088D03*
G54D40*
X99700Y113300D03*
X94985Y113275D03*
X163400Y189400D03*
X428000Y102700D03*
G54D22*
X90700Y100700D03*
X65300Y146900D03*
X167500Y189600D03*
X192000Y181500D03*
X404330Y4418D03*
X426919Y38224D03*
G54D31*
X98700Y57300D03*
X95700Y176400D03*
Y161400D03*
X59300Y154300D03*
X106178Y223217D03*
X63400Y207000D03*
X67400D03*
X71500D03*
X83500D03*
X95900D03*
X55900D03*
X108800Y45700D03*
X116671Y107765D03*
X120998Y107771D03*
X181152Y166642D03*
X185182D03*
X234200Y168000D03*
X301100Y171400D03*
X307000Y174700D03*
X411450Y-998D03*
X400200Y1100D03*
X413800Y19300D03*
X395130Y78202D03*
X399360D03*
X443445Y29607D03*
X450400Y37100D03*
X435287Y29608D03*
X436700Y112600D03*
X526110Y162502D03*
X517530Y162402D03*
G54D13*
X25300Y195900D03*
X44500D03*
X134900Y103000D03*
X154100D03*
X141000Y177100D03*
X121800D03*
G54D50*
X165800Y103800D03*
G54D14*
X103300Y14400D03*
X107600D03*
X95700Y168900D03*
X71726Y155766D03*
X75804Y155748D03*
X83300Y158500D03*
X67500Y154200D03*
X63400D03*
X105218Y141258D03*
X75500Y207000D03*
X79500D03*
X91700D03*
X87500D03*
X116000Y14500D03*
X111800D03*
X156300Y15200D03*
X157000Y70800D03*
X137000Y52900D03*
X175320Y173098D03*
X171290D03*
X171300Y186200D03*
X234300Y175700D03*
X327800Y35900D03*
X331500Y28200D03*
X332100Y36000D03*
X345700Y76900D03*
X336300Y35900D03*
X307000Y182200D03*
X413800Y11800D03*
X375600Y78300D03*
X422638Y80676D03*
X418444Y80647D03*
X426696Y80704D03*
X414283Y80676D03*
X371500Y78300D03*
X395148Y69558D03*
X399318D03*
X439418Y29635D03*
X530160Y162498D03*
X521600Y162398D03*
X534348Y162458D03*
X516810Y202098D03*
X512680D03*
G54D32*
X102900Y52600D03*
X71200Y163800D03*
X98089Y135908D03*
X98085Y140036D03*
X105650Y164312D03*
Y168512D03*
X101072Y148907D03*
X101043Y153241D03*
X59700Y168300D03*
X121198Y89357D03*
X128000Y51900D03*
Y47700D03*
Y43500D03*
X115800Y74800D03*
X160300Y66400D03*
X121302Y98010D03*
X168154Y198330D03*
X246400Y180600D03*
Y176500D03*
X246600Y193200D03*
X210500Y195800D03*
X246600Y189000D03*
X237600Y198500D03*
X330400Y19700D03*
X336200Y52200D03*
X334100Y64700D03*
X337800Y69600D03*
X286800Y168400D03*
X305511Y198009D03*
X305400Y193700D03*
Y189700D03*
X296800Y187800D03*
X377087Y17368D03*
X387100Y13200D03*
X387200Y3300D03*
X376900Y7400D03*
X377100Y21500D03*
X390300Y69500D03*
X390200Y59600D03*
X380000Y65400D03*
X380213Y55568D03*
X390200Y46600D03*
X380200Y50700D03*
X380100Y38400D03*
X387100Y25800D03*
X453794Y52538D03*
X453806Y48469D03*
X451660Y66541D03*
X458000Y37100D03*
X429865Y30637D03*
X429800Y26500D03*
X544602Y176160D03*
Y172130D03*
G54D23*
X90700Y97100D03*
X65300Y143300D03*
X167500Y186000D03*
X192000Y177900D03*
X404330Y818D03*
X426919Y34624D03*
G54D41*
X75300Y163800D03*
X94676Y131798D03*
X95955Y144059D03*
X55900Y176800D03*
X56298Y172400D03*
X117820Y93564D03*
X121800Y74600D03*
X108365Y105330D03*
X109205Y109777D03*
X180100Y118500D03*
X172326Y198299D03*
X194013Y116998D03*
X241400Y117600D03*
X226698Y171220D03*
Y175550D03*
X226634Y195198D03*
X243198Y197300D03*
X234200Y194400D03*
X246400Y184900D03*
X327000Y23900D03*
X332800Y56300D03*
Y60400D03*
X306500Y116400D03*
X293400Y167600D03*
Y171800D03*
X373300Y-1200D03*
X373500Y3300D03*
X373683Y13318D03*
X383700Y17300D03*
X383800Y7400D03*
X360200Y-1800D03*
X373700Y25600D03*
X376600Y69500D03*
X418800Y30700D03*
X386800Y55500D03*
X418700Y26400D03*
X378400Y34200D03*
Y30100D03*
X386900Y65400D03*
X376817Y59618D03*
X386800Y50700D03*
X376800Y46600D03*
Y42500D03*
X383700Y21700D03*
X447528Y29487D03*
G54D15*
X103300Y17800D03*
X107600D03*
X95700Y172300D03*
X71726Y159166D03*
X75804Y159148D03*
X83300Y161900D03*
X67500Y157600D03*
X63400D03*
X105218Y144658D03*
X75500Y210400D03*
X79500D03*
X91700D03*
X87500D03*
X116000Y17900D03*
X111800D03*
X156300Y18600D03*
X157000Y74200D03*
X137000Y56300D03*
X175320Y176498D03*
X171290D03*
X171300Y189600D03*
X234300Y179100D03*
X327800Y39300D03*
X331500Y31600D03*
X332100Y39400D03*
X345700Y80300D03*
X336300Y39300D03*
X307000Y185600D03*
X413800Y15200D03*
X375600Y81700D03*
X422638Y84076D03*
X418444Y84047D03*
X426696Y84104D03*
X414283Y84076D03*
X371500Y81700D03*
X395148Y72958D03*
X399318D03*
X439418Y33035D03*
X530160Y165898D03*
X521600Y165798D03*
X534348Y165858D03*
X516810Y205498D03*
X512680D03*
G54D24*
X50813Y89796D03*
X51465Y146761D03*
G54D33*
X99500Y52600D03*
X67800Y163800D03*
X94689Y135908D03*
X94685Y140036D03*
X102250Y164312D03*
Y168512D03*
X97672Y148907D03*
X97643Y153241D03*
X56300Y168300D03*
X117798Y89357D03*
X124600Y51900D03*
Y47700D03*
Y43500D03*
X112400Y74800D03*
X156900Y66400D03*
X117902Y98010D03*
X164754Y198330D03*
X243000Y180600D03*
Y176500D03*
X243200Y193200D03*
X207100Y195800D03*
X243200Y189000D03*
X234200Y198500D03*
X327000Y19700D03*
X332800Y52200D03*
X330700Y64700D03*
X334400Y69600D03*
X283400Y168400D03*
X302111Y198009D03*
X302000Y193700D03*
Y189700D03*
X293400Y187800D03*
X373687Y17368D03*
X383700Y13200D03*
X383800Y3300D03*
X373500Y7400D03*
X373700Y21500D03*
X426465Y30637D03*
X426400Y26500D03*
X386900Y69500D03*
X386800Y59600D03*
X376600Y65400D03*
X376813Y55568D03*
X386800Y46600D03*
X376800Y50700D03*
X376700Y38400D03*
X383700Y25800D03*
X450394Y52538D03*
X450406Y48469D03*
X448260Y66541D03*
X454600Y37100D03*
X541202Y176160D03*
Y172130D03*
G54D42*
X78700Y163800D03*
X98076Y131798D03*
X99355Y144059D03*
X59300Y176800D03*
X59698Y172400D03*
X121220Y93564D03*
X125200Y74600D03*
X111765Y105330D03*
X112605Y109777D03*
X183500Y118500D03*
X175726Y198299D03*
X197413Y116998D03*
X244800Y117600D03*
X230098Y171220D03*
Y175550D03*
X230034Y195198D03*
X246598Y197300D03*
X237600Y194400D03*
X249800Y184900D03*
X330400Y23900D03*
X336200Y56300D03*
Y60400D03*
X309900Y116400D03*
X296800Y167600D03*
Y171800D03*
X376700Y-1200D03*
X376900Y3300D03*
X377083Y13318D03*
X387100Y17300D03*
X387200Y7400D03*
X363600Y-1800D03*
X377100Y25600D03*
X380000Y69500D03*
X422200Y30700D03*
X390200Y55500D03*
X422100Y26400D03*
X381800Y34200D03*
Y30100D03*
X390300Y65400D03*
X380217Y59618D03*
X390200Y50700D03*
X380200Y46600D03*
Y42500D03*
X387100Y21700D03*
X450928Y29487D03*
G54D60*
X433627Y88710D03*
X451395Y78376D03*
G54D51*
X171400Y103800D03*
G54D25*
X53357Y92340D03*
X54009Y149305D03*
G54D16*
X109200Y-26200D03*
Y-15200D03*
G54D61*
X468381Y66114D03*
X459157D03*
Y72070D03*
X468381D03*
G54D34*
X101722Y86658D03*
X103691D03*
X105659D03*
Y98870D03*
X103691D03*
X101722D03*
X76226Y134181D03*
X78195D03*
X80163D03*
X82132D03*
Y146393D03*
X80163D03*
X78195D03*
X76226D03*
X107628Y86658D03*
Y98870D03*
G54D43*
X66197Y173644D03*
X68757D03*
X71317D03*
X73877D03*
X76437D03*
X78997D03*
X81557D03*
X84117D03*
X86677D03*
X89237D03*
Y195844D03*
X86677D03*
X84117D03*
X81557D03*
X78997D03*
X76437D03*
X73877D03*
X71317D03*
X68757D03*
X66197D03*
X205780Y172408D03*
X203220D03*
X200660D03*
X198100D03*
Y188588D03*
X200660D03*
X203220D03*
X205780D03*
X402330Y12412D03*
X399770D03*
X397210D03*
X394650D03*
Y28592D03*
X397210D03*
X399770D03*
X402330D03*
G54D52*
X259944Y178583D03*
Y176023D03*
Y173463D03*
Y196503D03*
Y193943D03*
Y191383D03*
Y188823D03*
Y186263D03*
Y183703D03*
Y181143D03*
X341438Y2889D03*
Y5449D03*
Y8009D03*
Y10569D03*
Y13129D03*
Y15689D03*
Y18249D03*
Y20809D03*
Y23369D03*
Y25929D03*
Y28489D03*
Y31049D03*
X344638Y39889D03*
Y42449D03*
Y45009D03*
Y47569D03*
Y50129D03*
Y52689D03*
Y55249D03*
Y57809D03*
Y60369D03*
Y62929D03*
Y65489D03*
Y68049D03*
X282144Y173463D03*
Y176023D03*
Y178583D03*
Y181143D03*
Y183703D03*
Y186263D03*
Y188823D03*
Y191383D03*
Y193943D03*
Y196503D03*
X363638Y18249D03*
Y15689D03*
Y13129D03*
Y10569D03*
Y8009D03*
Y5449D03*
Y2889D03*
Y31049D03*
Y28489D03*
Y25929D03*
Y23369D03*
Y20809D03*
X366838Y68049D03*
Y65489D03*
Y62929D03*
Y60369D03*
Y57809D03*
Y55249D03*
Y52689D03*
Y50129D03*
Y47569D03*
Y45009D03*
Y42449D03*
Y39889D03*
G54D26*
X102500Y65800D03*
X59600Y206900D03*
X133100Y56200D03*
X520600Y196600D03*
G54D17*
X85400Y48400D03*
X89978Y126933D03*
X95068Y126988D03*
X99160Y229024D03*
X89548Y229126D03*
X94401Y229011D03*
X84631Y229140D03*
X157100Y84400D03*
X434600Y21600D03*
G54D53*
X418345Y44560D03*
Y67560D03*
X434093Y44560D03*
Y67560D03*
G54D62*
X515814Y178749D03*
X528026D03*
X515814Y184655D03*
Y182686D03*
Y180718D03*
X528026D03*
Y182686D03*
Y184655D03*
G54D35*
X98569Y95717D03*
Y93748D03*
Y91780D03*
Y89811D03*
X73073Y143240D03*
Y141271D03*
Y139303D03*
Y137334D03*
X85285D03*
Y139303D03*
Y141271D03*
Y143240D03*
X110781Y89811D03*
Y91780D03*
Y93748D03*
Y95717D03*
G54D44*
X40794Y230682D03*
X37095Y524125D03*
X540347Y32747D03*
X572386Y532294D03*
X601314Y-26920D03*
X599868Y229462D03*
G54D27*
X102500Y69400D03*
X59600Y210500D03*
X133100Y59800D03*
X520600Y200200D03*
G54D54*
X414719Y63934D03*
Y48186D03*
X437719D03*
Y63934D03*
G54D63*
X518967Y175596D03*
X520936D03*
X522904D03*
X524873D03*
Y187808D03*
X522904D03*
X520936D03*
X518967D03*
G54D45*
X150588Y-42D03*
X153148D03*
X155708D03*
Y7358D03*
X153148D03*
X150588D03*
G54D36*
X104675Y92764D03*
X79179Y140287D03*
X521920Y181702D03*
G54D18*
X85400Y42800D03*
X89978Y121333D03*
X95068Y121388D03*
X99160Y223424D03*
X89548Y223526D03*
X94401Y223411D03*
X84631Y223540D03*
X157100Y78800D03*
X434600Y16000D03*
G54D28*
X91600Y91200D03*
X65600Y139400D03*
X170600Y107900D03*
X108667Y187305D03*
X108673Y190847D03*
X108588Y183478D03*
X404900Y54873D03*
X404961Y51269D03*
X407955Y65607D03*
X366800Y72500D03*
X461441Y60110D03*
X527900Y196300D03*
G54D19*
X47930Y92365D03*
X50813Y95248D03*
X48691Y149395D03*
X51535Y152305D03*
G54D64*
X524430Y224202D03*
Y231802D03*
X532360Y224202D03*
Y231802D03*
X540290Y224202D03*
Y231802D03*
X548220Y224202D03*
Y231802D03*
G54D55*
X415019Y50154D03*
Y52123D03*
Y54091D03*
Y56060D03*
Y58029D03*
Y59997D03*
Y61966D03*
X437419D03*
Y59997D03*
Y58029D03*
Y56060D03*
Y54091D03*
Y52123D03*
Y50154D03*
G54D46*
X157100Y62300D03*
X143000Y86000D03*
Y82400D03*
Y78700D03*
X289000Y196800D03*
X365600Y35400D03*
X408700Y33400D03*
X447520Y33313D03*
X465391Y60100D03*
X447388Y74043D03*
X450400Y44300D03*
X431634Y84295D03*
X448831Y60176D03*
X513082Y198350D03*
G54D37*
X71000Y100900D03*
Y120100D03*
G54D65*
G01X-84798Y-164972D02*
Y-244972D01*
G01D02*
X1172402D01*
G01X-88798Y-148972D02*
G02I-12000J0D01*
G01X-93948D02*
G02I-6850J0D01*
G01X-100798Y-164972D02*
Y-132972D01*
G01X-84798Y-148972D02*
X-116798D01*
G01X-84798Y-164972D02*
X1172402D01*
G01X-84798Y-200472D02*
X1172402D01*
G01X384902Y-164972D02*
Y-244972D01*
G01X522402Y-164972D02*
Y-244972D01*
G01X637402Y-164972D02*
Y-244972D01*
G01X804902Y-164972D02*
Y-244972D01*
G01X974902Y-164972D02*
Y-244972D01*
G01X1172402Y-164972D02*
Y-244972D01*
G01X1200402Y-148972D02*
G02I-12000J0D01*
G01X1195252D02*
G02I-6850J0D01*
G01X1188402Y-164972D02*
Y-132972D01*
G01X1204402Y-148972D02*
X1172402D01*
G54D29*
X88000Y91200D03*
X62000Y139400D03*
X105067Y187305D03*
X105073Y190847D03*
X104988Y183478D03*
X167000Y107900D03*
X401300Y54873D03*
X401361Y51269D03*
X404355Y65607D03*
X363200Y72500D03*
X457841Y60110D03*
X524300Y196300D03*
G54D38*
X92700Y34400D03*
X103700D03*
X509994Y212056D03*
X520994D03*
G54D56*
X426219Y44860D03*
X424250D03*
X422282D03*
X420313D03*
Y67260D03*
X422282D03*
X424250D03*
X426219D03*
X432125Y44860D03*
X430156D03*
X428188D03*
Y67260D03*
X430156D03*
X432125D03*
G54D47*
X160700Y62300D03*
X146600Y86000D03*
Y82400D03*
Y78700D03*
X292600Y196800D03*
X369200Y35400D03*
X412300Y33400D03*
X451120Y33313D03*
X468991Y60100D03*
X450988Y74043D03*
X454000Y44300D03*
X435234Y84295D03*
X452431Y60176D03*
X516682Y198350D03*
G54D66*
G01X-21653Y-58346D02*
G03X-6653Y-73346I15000J0D01*
G01X65080D02*
X-6653D01*
G01X9506Y0D02*
X69017D01*
G01X6722Y1153D02*
G03X9506Y0I2784J2784D01*
G01X1154Y6721D02*
X6722Y1153D01*
G01X1Y9505D02*
G03X1154Y6721I3937J0D01*
G01X1Y238051D02*
Y9505D01*
G01Y238051D02*
Y9505D01*
G01X-21653Y238051D02*
Y9505D01*
G01X1D02*
G03X1154Y6721I3937J0D01*
G01X-7873Y9505D02*
G03X-4414Y1153I11811J-1D01*
G01X1154Y6721D02*
X6722Y1153D01*
G01X-4414D02*
X1154Y-4415D01*
G01X6722Y1153D02*
G03X9506Y0I2784J2784D01*
G01X1154Y-4415D02*
G03X9506Y-7874I8351J8352D01*
G01Y0D02*
X69017D01*
G01X9506Y-7874D02*
X14917D01*
G01X-21653Y9505D02*
Y-58346D01*
G01X14917Y-7874D02*
G03Y0I0J3937D01*
G01X-7873Y50852D02*
Y9505D01*
G01Y81561D02*
G03X1I3937J-1D01*
G01Y50852D02*
G03X-7873I-3937J0D01*
G01Y186482D02*
Y81561D01*
G01X13443Y249862D02*
X611812D01*
G01X10659Y251015D02*
G03X13443Y249862I2784J2784D01*
G01X1154Y260520D02*
X10659Y251015D01*
G01X3938Y241988D02*
G03X1Y238051I0J-3937D01*
G01X602307Y241988D02*
X3938D01*
G01X602307D02*
X3938D01*
G01D02*
G03X1Y238051I0J-3937D01*
G01X-7873D02*
Y217191D01*
G01X1154Y260520D02*
X10659Y251015D01*
G01D02*
G03X13443Y249862I2784J2784D01*
G01D02*
X611812D01*
G01X-21653Y238051D02*
Y534327D01*
G01X-7873Y238051D02*
Y263304D01*
G01Y217191D02*
G03X1I3937J-1D01*
G01Y186482D02*
G03X-7873I-3937J0D01*
G01X1Y263304D02*
G03X1154Y260520I3937J0D01*
G01X1Y328602D02*
Y263304D01*
G01X3938Y332539D02*
G03X1Y328602I0J-3937D01*
G01X53151Y332539D02*
X3938D01*
G01X53151D02*
X3938D01*
G01D02*
G03X1Y328602I0J-3937D01*
G01X3938Y340413D02*
G03X-7873Y328602I0J-11811D01*
G01X1D02*
Y263304D01*
G01X-7873Y328602D02*
Y263304D01*
G01X1D02*
G03X1154Y260520I3937J0D01*
G01X10965Y332539D02*
G03Y340413I0J3937D01*
G01D02*
X3938D01*
G01X-6653Y565196D02*
G03X-21653Y550196I0J-15000D01*
G01X67796Y565196D02*
X-6653D01*
G01X-21653Y542201D02*
Y550196D01*
G01Y534327D02*
G03Y542201I0J3937D01*
G01X74922Y-73346D02*
X175828D01*
G01X72954Y-71378D02*
X74922Y-73346D01*
G01X72954Y-3937D02*
Y-71378D01*
G01X65080Y-7874D02*
Y-71772D01*
G01D02*
Y-73346D01*
G01X72954Y-3937D02*
G03X69017Y0I-3937J0D01*
G01X72954Y-3937D02*
G03X69017Y0I-3937J0D01*
G01X45626D02*
G03Y-7874I0J-3937D01*
G01D02*
X65080D01*
G01X51397Y241988D02*
G03Y249862I0J3937D01*
G01X93906D02*
G03Y241988I0J-3937D01*
G01X53151Y332539D02*
G03X57088Y336476I0J3937D01*
G01Y482345D02*
Y336476D01*
G01Y482345D02*
Y336476D01*
G01X53151Y332539D02*
G03X57088Y336476I0J3937D01*
G01X41674Y340413D02*
G03Y332539I0J-3937D01*
G01X49214Y340413D02*
X41674D01*
G01X49214Y442487D02*
Y340413D01*
G01X67796Y565196D02*
Y499724D01*
G01X75670Y563228D02*
Y495787D01*
G01X58241Y485129D02*
G03X57088Y482345I2784J-2784D01*
G01X63808Y490697D02*
X58241Y485129D01*
G01X66592Y491850D02*
G03X63808Y490697I0J-3937D01*
G01X71733Y491850D02*
X66592D01*
G01X71733D02*
G03X75670Y495787I0J3937D01*
G01X67796Y499724D02*
X66592D01*
G01Y491850D02*
G03X63808Y490697I0J-3937D01*
G01X66592Y499724D02*
G03X58240Y496265I-1J-11811D01*
G01X63808Y490697D02*
X58241Y485129D01*
G01X58240Y496264D02*
X52673Y490696D01*
G01X58241Y485129D02*
G03X57088Y482345I2784J-2784D01*
G01X52673Y490697D02*
G03X49214Y482343I8352J-8351D01*
G01Y482345D02*
Y473195D01*
G01X57088Y442487D02*
G03X49214I-3937J-1D01*
G01Y473195D02*
G03X57088I3937J0D01*
G01X77639Y565196D02*
X75670Y563228D01*
G01X173111Y565196D02*
X77639D01*
G01X177796Y-71378D02*
Y-52874D01*
G01X175828Y-73346D02*
X177796Y-71378D01*
G01X187245Y-52874D02*
G03X177796I-4725J0D01*
G01X175080Y563228D02*
X173111Y565196D01*
G01X175080Y534488D02*
Y563228D01*
G01Y534488D02*
G03X175867Y533700I787J-1D01*
G01X209529D02*
X175867D01*
G01X189214Y-73346D02*
X403466D01*
G01X187245Y-71378D02*
X189214Y-73346D01*
G01X187245Y-52874D02*
Y-71378D01*
G01X209529Y533700D02*
G03X210316Y534488I0J787D01*
G01Y563228D02*
Y534488D01*
G01X212284Y565196D02*
X210316Y563228D01*
G01X426536Y565196D02*
X212284D01*
G01X405434Y-71378D02*
Y-42638D01*
G01X403466Y-73346D02*
X405434Y-71378D01*
G01X406221Y-41850D02*
X439883D01*
G01X406221D02*
G03X405434Y-42638I1J-788D01*
G01X428505Y563228D02*
X426536Y565196D01*
G01X442639Y-73346D02*
X538111D01*
G01X440670Y-71378D02*
X442639Y-73346D01*
G01X440670Y-42638D02*
Y-71378D01*
G01Y-42638D02*
G03X439883Y-41850I-787J1D01*
G01X428504Y544723D02*
Y563227D01*
G01Y544723D02*
G03X437953I4724J0D01*
G01Y563227D02*
Y544723D01*
G01X428505Y544724D02*
Y563228D01*
G01Y544724D02*
G03X437954I4725J0D01*
G01Y563228D02*
Y544724D01*
G01X439922Y565196D02*
X437954Y563228D01*
G01X540828Y565196D02*
X439922D01*
G01X547954Y-73346D02*
X622403D01*
G01X547954D02*
Y-7874D01*
G01X540080Y-71378D02*
Y-3937D01*
G01X538111Y-73346D02*
X540080Y-71378D01*
G01X558662Y9505D02*
Y155374D01*
G01X557509Y6721D02*
G03X558662Y9505I-2784J2784D01*
G01X551942Y1153D02*
X557509Y6721D01*
G01X549158Y0D02*
G03X551942Y1153I0J3937D01*
G01X544017Y0D02*
X549158D01*
G01X544017D02*
G03X540080Y-3937I0J-3937D01*
G01X547954Y-7874D02*
X549158D01*
G01Y0D02*
G03X551942Y1153I0J3937D01*
G01X549158Y-7875D02*
G03X557510Y-4415I0J11811D01*
G01X551942Y1153D02*
X557509Y6721D01*
G01X557510Y-4414D02*
X563077Y1154D01*
G01X557509Y6721D02*
G03X558662Y9505I-2784J2784D01*
G01X563077Y1153D02*
G03X566536Y9507I-8352J8351D01*
G01X558662Y9505D02*
Y155374D01*
G01X566536Y9505D02*
Y18655D01*
G01D02*
G03X558662I-3937J-1D01*
G01Y49363D02*
G03X566536I3937J0D01*
G01D02*
Y151437D01*
G01X562599Y159311D02*
X611812D01*
G01X562599D02*
G03X558662Y155374I0J-3937D01*
G01X562599Y159311D02*
G03X558662Y155374I0J-3937D01*
G01X562599Y159311D02*
X611812D01*
G01X566536Y151437D02*
X574076D01*
G01D02*
G03Y159311I0J3937D01*
G01X564353Y249862D02*
G03Y241988I0J-3937D01*
G01X521844D02*
G03Y249862I0J3937D01*
G01X542796Y495787D02*
Y563228D01*
G01Y495787D02*
G03X546733Y491850I3937J0D01*
G01X606244D02*
X546733D01*
G01X606244D02*
X546733D01*
G01X542796Y495787D02*
G03X546733Y491850I3937J0D01*
G01X550670Y499724D02*
Y563622D01*
G01X570124Y491850D02*
G03Y499724I0J3937D01*
G01D02*
X550670D01*
G01Y565196D02*
X622403D01*
G01X542796Y563228D02*
X540828Y565196D01*
G01X550670Y563622D02*
Y565196D01*
G01X622403Y-73346D02*
G03X637403Y-58346I0J15000D01*
G01Y253799D02*
Y-58346D01*
G01X615749Y163248D02*
Y228546D01*
G01X611812Y159311D02*
G03X615749Y163248I0J3937D01*
G01X611812Y159311D02*
G03X615749Y163248I0J3937D01*
G01X611812Y151437D02*
G03X623623Y163248I0J11811D01*
G01X615749D02*
Y228546D01*
G01X623623Y163248D02*
Y228546D01*
G01X604785Y159311D02*
G03Y151437I0J-3937D01*
G01D02*
X611812D01*
G01X615749Y253799D02*
Y482345D01*
G01X611812Y249862D02*
G03X615749Y253799I0J3937D01*
G01X605091Y240835D02*
G03X602307Y241988I-2784J-2784D01*
G01X614596Y231330D02*
X605091Y240835D01*
G01X615749Y228546D02*
G03X614596Y231330I-3937J0D01*
G01X615749Y228546D02*
G03X614596Y231330I-3937J0D01*
G01D02*
X605091Y240835D01*
G01D02*
G03X602307Y241988I-2784J-2784D01*
G01X611812Y249862D02*
G03X615749Y253799I0J3937D01*
G01D02*
Y482345D01*
G01X623623Y253799D02*
Y274659D01*
G01X637403Y253799D02*
Y482345D01*
G01X623623Y228546D02*
Y253799D01*
G01Y274659D02*
G03X615749I-3937J0D01*
G01Y305368D02*
G03X623623I3937J0D01*
G01D02*
Y410289D01*
G01D02*
G03X615749I-3937J0D01*
G01X609028Y490697D02*
G03X606244Y491850I-2784J-2784D01*
G01X614596Y485129D02*
X609028Y490697D01*
G01X615749Y482345D02*
G03X614596Y485129I-3937J0D01*
G01X615749Y482345D02*
G03X614596Y485129I-3937J0D01*
G01X623623Y482345D02*
G03X620164Y490697I-11811J1D01*
G01X614596Y485129D02*
X609028Y490697D01*
G01X620164D02*
X614596Y496265D01*
G01X609028Y490697D02*
G03X606244Y491850I-2784J-2784D01*
G01X614596Y496265D02*
G03X606244Y499724I-8351J-8352D01*
G01D02*
X600833D01*
G01X637403Y482345D02*
Y550196D01*
G01X600833Y499724D02*
G03Y491850I0J-3937D01*
G01X615749Y440998D02*
G03X623623I3937J0D01*
G01D02*
Y482345D01*
G01X637403Y550196D02*
G03X622403Y565196I-15000J0D01*
G54D48*
X142400Y66700D03*
Y58700D03*
X151200Y62700D03*
G54D57*
X426219Y56060D03*
G54D39*
X99700Y107700D03*
X94985Y107675D03*
X163400Y183800D03*
X428000Y97100D03*
G54D67*
G01X-65001Y-234972D02*
Y-217472D01*
X-60635D01*
X-58888Y-218347D01*
X-57578Y-219514D01*
X-56486Y-221263D01*
X-55613Y-223306D01*
X-55395Y-226222D01*
X-55613Y-229139D01*
X-56486Y-231181D01*
X-57578Y-232931D01*
X-58888Y-234097D01*
X-60635Y-234972D01*
X-65001D01*
G01X-48157Y-217472D02*
X-42698Y-234972D01*
X-37239Y-217472D01*
G01X-25198D02*
Y-234972D01*
G01X-30220Y-217472D02*
X-20176D01*
G01X5435Y-234972D02*
Y-217472D01*
X10894D01*
X12640Y-218347D01*
X13732Y-219514D01*
X14169Y-221847D01*
X13732Y-224181D01*
X12422Y-225639D01*
X10894Y-226514D01*
X5435D01*
G01X10894D02*
X14169Y-234972D01*
G01X27302Y-223306D02*
Y-234972D01*
G01Y-218639D02*
X26865Y-218347D01*
Y-217764D01*
X27302Y-217472D01*
X27739Y-217764D01*
Y-218347D01*
X27302Y-218639D01*
G01X41527Y-232931D02*
X42619Y-234097D01*
X44147Y-234972D01*
X45457D01*
X46767Y-234389D01*
X47640Y-233514D01*
X48077Y-232348D01*
X47859Y-230597D01*
X46985Y-229722D01*
X43055Y-227972D01*
X42182Y-225930D01*
X42619Y-224472D01*
X43492Y-223597D01*
X44802Y-223306D01*
X46112Y-223597D01*
X47422Y-224472D01*
G01X59027Y-227097D02*
X66014D01*
X65359Y-225055D01*
X64267Y-223889D01*
X62739Y-223306D01*
X61210Y-223597D01*
X59900Y-224472D01*
X59027Y-226514D01*
X58590Y-228264D01*
Y-230014D01*
X59027Y-231764D01*
X60119Y-233514D01*
X61429Y-234680D01*
X62957Y-234972D01*
X64485Y-234389D01*
X66014Y-232639D01*
G01X76745Y-234972D02*
Y-223306D01*
G01Y-225639D02*
X77837Y-224472D01*
X78929Y-223597D01*
X80457Y-223306D01*
X81548Y-223597D01*
X82859Y-224472D01*
G01X119605Y-218931D02*
X118295Y-218055D01*
X116767Y-217472D01*
X115020D01*
X113055Y-218347D01*
X111527Y-219805D01*
X110435Y-221556D01*
X109562Y-224472D01*
X109343Y-227097D01*
X109780Y-229722D01*
X110435Y-231472D01*
X111745Y-233222D01*
X113274Y-234389D01*
X114802Y-234972D01*
X116330D01*
X117859Y-234389D01*
X119169Y-233514D01*
X120261Y-232348D01*
G01X136232Y-234972D02*
Y-223306D01*
G01Y-225347D02*
X135359Y-224181D01*
X134048Y-223597D01*
X132520Y-223306D01*
X130992Y-223889D01*
X129682Y-225055D01*
X128808Y-226805D01*
X128372Y-229139D01*
X128808Y-231472D01*
X129682Y-233222D01*
X130992Y-234389D01*
X132520Y-234972D01*
X134048Y-234680D01*
X135359Y-233806D01*
X136232Y-232639D01*
G01X146745Y-234972D02*
Y-223306D01*
G01Y-225639D02*
X147837Y-224472D01*
X148929Y-223597D01*
X150457Y-223306D01*
X151548Y-223597D01*
X152859Y-224472D01*
G01X171232Y-217472D02*
Y-234972D01*
G01Y-232348D02*
X170359Y-233806D01*
X169048Y-234680D01*
X167520Y-234972D01*
X165774Y-234389D01*
X164464Y-232931D01*
X163590Y-231181D01*
X163372Y-229139D01*
X163590Y-227097D01*
X164464Y-225347D01*
X165774Y-223889D01*
X167520Y-223306D01*
X169048Y-223597D01*
X170140Y-224181D01*
X171232Y-225347D01*
G01X178252Y-240805D02*
X191352D01*
G01X197717Y-232639D02*
X199464Y-234097D01*
X201429Y-234972D01*
X203175D01*
X204922Y-234097D01*
X206232Y-232639D01*
X206887Y-230597D01*
X206450Y-228556D01*
X205359Y-226805D01*
X203394Y-225639D01*
X200774Y-225055D01*
X199245Y-223889D01*
X198590Y-221847D01*
X199027Y-219805D01*
X200119Y-218347D01*
X201647Y-217472D01*
X203175D01*
X204704Y-218055D01*
X206014Y-219514D01*
G01X215217Y-232639D02*
X216964Y-234097D01*
X218929Y-234972D01*
X220675D01*
X222422Y-234097D01*
X223732Y-232639D01*
X224387Y-230597D01*
X223950Y-228556D01*
X222859Y-226805D01*
X220894Y-225639D01*
X218274Y-225055D01*
X216745Y-223889D01*
X216090Y-221847D01*
X216527Y-219805D01*
X217619Y-218347D01*
X219147Y-217472D01*
X220675D01*
X222204Y-218055D01*
X223514Y-219514D01*
G01X250654Y-220389D02*
X251964Y-218639D01*
X253492Y-217764D01*
X255239Y-217472D01*
X257422Y-218055D01*
X258950Y-219514D01*
X259387Y-221263D01*
X259169Y-223014D01*
X258295Y-224472D01*
X253929Y-227389D01*
X251964Y-229430D01*
X250654Y-232348D01*
X250217Y-234972D01*
X259387D01*
G01X286527Y-232931D02*
X287619Y-234097D01*
X289147Y-234972D01*
X290457D01*
X291767Y-234389D01*
X292640Y-233514D01*
X293077Y-232348D01*
X292859Y-230597D01*
X291985Y-229722D01*
X288055Y-227972D01*
X287182Y-225930D01*
X287619Y-224472D01*
X288492Y-223597D01*
X289802Y-223306D01*
X291112Y-223597D01*
X292422Y-224472D01*
G01X307302Y-234972D02*
Y-217472D01*
G01X324802Y-234972D02*
X323492Y-234680D01*
X322182Y-233514D01*
X321308Y-231472D01*
X320872Y-229139D01*
X321308Y-226805D01*
X322182Y-224764D01*
X323492Y-223597D01*
X324802Y-223306D01*
X326112Y-223597D01*
X327422Y-224764D01*
X328295Y-226805D01*
X328514Y-229139D01*
X328295Y-231472D01*
X327422Y-233514D01*
X326112Y-234680D01*
X324802Y-234972D01*
G01X342302Y-217472D02*
Y-234972D01*
G01X339245Y-223306D02*
X345359D01*
G01X356527Y-232931D02*
X357619Y-234097D01*
X359147Y-234972D01*
X360457D01*
X361767Y-234389D01*
X362640Y-233514D01*
X363077Y-232348D01*
X362859Y-230597D01*
X361985Y-229722D01*
X358055Y-227972D01*
X357182Y-225930D01*
X357619Y-224472D01*
X358492Y-223597D01*
X359802Y-223306D01*
X361112Y-223597D01*
X362422Y-224472D01*
G01X109125Y-189972D02*
Y-172472D01*
X114802Y-187055D01*
X120479Y-172472D01*
Y-189972D01*
G01X132302D02*
X130992Y-189680D01*
X129682Y-188514D01*
X128808Y-186472D01*
X128372Y-184139D01*
X128808Y-181805D01*
X129682Y-179764D01*
X130992Y-178597D01*
X132302Y-178306D01*
X133612Y-178597D01*
X134922Y-179764D01*
X135795Y-181805D01*
X136014Y-184139D01*
X135795Y-186472D01*
X134922Y-188514D01*
X133612Y-189680D01*
X132302Y-189972D01*
G01X153732Y-172472D02*
Y-189972D01*
G01Y-187348D02*
X152859Y-188806D01*
X151548Y-189680D01*
X150020Y-189972D01*
X148274Y-189389D01*
X146964Y-187931D01*
X146090Y-186181D01*
X145872Y-184139D01*
X146090Y-182097D01*
X146964Y-180347D01*
X148274Y-178889D01*
X150020Y-178306D01*
X151548Y-178597D01*
X152640Y-179181D01*
X153732Y-180347D01*
G01X164027Y-182097D02*
X171014D01*
X170359Y-180055D01*
X169267Y-178889D01*
X167739Y-178306D01*
X166210Y-178597D01*
X164900Y-179472D01*
X164027Y-181514D01*
X163590Y-183264D01*
Y-185014D01*
X164027Y-186764D01*
X165119Y-188514D01*
X166429Y-189680D01*
X167957Y-189972D01*
X169485Y-189389D01*
X171014Y-187639D01*
G01X184802Y-189972D02*
Y-172472D01*
G01X418602Y-234972D02*
Y-217472D01*
X415982Y-220972D01*
G01Y-234972D02*
X421222D01*
G01X431299Y-232348D02*
X432608Y-233806D01*
X434137Y-234680D01*
X436102Y-234972D01*
X438067Y-234389D01*
X439595Y-233222D01*
X440687Y-231181D01*
X440905Y-228847D01*
X440469Y-226514D01*
X439377Y-225055D01*
X437848Y-223889D01*
X436320Y-223597D01*
X434792Y-223889D01*
X432827Y-225055D01*
X433482Y-217472D01*
X439377D01*
G01X449890Y-232931D02*
X451419Y-234389D01*
X453165Y-234972D01*
X454912Y-234389D01*
X456440Y-232639D01*
X457532Y-230014D01*
X457969Y-227389D01*
Y-224181D01*
X457532Y-221556D01*
X456440Y-219222D01*
X455130Y-218055D01*
X453602Y-217472D01*
X451855Y-218055D01*
X450545Y-219222D01*
X449672Y-220972D01*
X449235Y-223306D01*
X449672Y-225347D01*
X450764Y-227389D01*
X452074Y-228556D01*
X453602Y-228847D01*
X455348Y-228264D01*
X456659Y-226805D01*
X457969Y-224181D01*
G01X466954Y-227681D02*
X468482Y-225639D01*
X469792Y-224472D01*
X471539Y-223889D01*
X473067Y-224472D01*
X474159Y-225639D01*
X475032Y-227389D01*
X475250Y-229430D01*
X475032Y-231181D01*
X474159Y-232931D01*
X472848Y-234389D01*
X471320Y-234972D01*
X469574Y-234389D01*
X468045Y-232639D01*
X467172Y-230014D01*
X466954Y-227097D01*
X467390Y-223306D01*
X468045Y-221263D01*
X469137Y-219222D01*
X470665Y-217764D01*
X472194Y-217472D01*
X473722Y-218055D01*
X474814Y-219514D01*
G01X488602Y-234972D02*
X490130Y-234680D01*
X491877Y-233806D01*
X492969Y-232348D01*
X493405Y-230305D01*
X492969Y-228264D01*
X491659Y-226514D01*
X489694Y-225639D01*
X487510D01*
X486200Y-225055D01*
X485108Y-223597D01*
X484672Y-221556D01*
X485327Y-219514D01*
X486855Y-218055D01*
X488602Y-217472D01*
X490348Y-218055D01*
X491877Y-219514D01*
X492532Y-221556D01*
X492095Y-223597D01*
X491004Y-225055D01*
X489694Y-225639D01*
X487510D01*
X485545Y-226514D01*
X484235Y-228264D01*
X483799Y-230305D01*
X484235Y-232348D01*
X485327Y-233806D01*
X487074Y-234680D01*
X488602Y-234972D01*
G01X405485Y-189972D02*
Y-172472D01*
X410725D01*
X412472Y-173347D01*
X413782Y-175389D01*
X414219Y-177722D01*
X413782Y-180055D01*
X412690Y-181805D01*
X410725Y-182681D01*
X405485D01*
G01X432155Y-173931D02*
X430845Y-173055D01*
X429317Y-172472D01*
X427570D01*
X425605Y-173347D01*
X424077Y-174805D01*
X422985Y-176556D01*
X422112Y-179472D01*
X421893Y-182097D01*
X422330Y-184722D01*
X422985Y-186472D01*
X424295Y-188222D01*
X425824Y-189389D01*
X427352Y-189972D01*
X428880D01*
X430409Y-189389D01*
X431719Y-188514D01*
X432811Y-187348D01*
G01X446598Y-180639D02*
X447472Y-179764D01*
X448127Y-178306D01*
X448564Y-176263D01*
X448127Y-174514D01*
X447254Y-173347D01*
X445725Y-172472D01*
X439830D01*
Y-189972D01*
X447035D01*
X448564Y-188806D01*
X449437Y-187055D01*
X449874Y-185014D01*
X449437Y-182972D01*
X448127Y-181222D01*
X446598Y-180639D01*
X439830D01*
G01X455802Y-195805D02*
X468902D01*
G01X474830Y-189972D02*
Y-172472D01*
X484874Y-189972D01*
Y-172472D01*
G01X497352Y-189972D02*
X495605Y-189680D01*
X494077Y-188514D01*
X492767Y-186764D01*
X491893Y-184722D01*
X491457Y-182389D01*
Y-180055D01*
X491893Y-177722D01*
X492767Y-175680D01*
X494077Y-173931D01*
X495605Y-172764D01*
X497352Y-172472D01*
X499098Y-172764D01*
X500627Y-173931D01*
X501937Y-175680D01*
X502811Y-177722D01*
X503247Y-180055D01*
Y-182389D01*
X502811Y-184722D01*
X501937Y-186764D01*
X500627Y-188514D01*
X499098Y-189680D01*
X497352Y-189972D01*
G01X571152Y-234972D02*
Y-217472D01*
X568532Y-220972D01*
G01Y-234972D02*
X573772D01*
G01X583193D02*
X588652Y-217472D01*
X594111Y-234972D01*
G01X592145Y-228847D02*
X585158D01*
G01X548193Y-172472D02*
X553652Y-189972D01*
X559111Y-172472D01*
G01X575519Y-189972D02*
X566785D01*
Y-172472D01*
X575519D01*
G01X572025Y-180930D02*
X566785D01*
G01X584285Y-189972D02*
Y-172472D01*
X589744D01*
X591490Y-173347D01*
X592582Y-174514D01*
X593019Y-176847D01*
X592582Y-179181D01*
X591272Y-180639D01*
X589744Y-181514D01*
X584285D01*
G01X589744D02*
X593019Y-189972D01*
G01X606152Y-190555D02*
X605715Y-190264D01*
Y-189680D01*
X606152Y-189389D01*
X606589Y-189680D01*
Y-190264D01*
X606152Y-190555D01*
G01X694852Y-217472D02*
Y-234972D01*
G01X689830Y-217472D02*
X699874D01*
G01X707767Y-232639D02*
X709514Y-234097D01*
X711479Y-234972D01*
X713225D01*
X714972Y-234097D01*
X716282Y-232639D01*
X716937Y-230597D01*
X716500Y-228556D01*
X715409Y-226805D01*
X713444Y-225639D01*
X710824Y-225055D01*
X709295Y-223889D01*
X708640Y-221847D01*
X709077Y-219805D01*
X710169Y-218347D01*
X711697Y-217472D01*
X713225D01*
X714754Y-218055D01*
X716064Y-219514D01*
G01X724175Y-234972D02*
Y-217472D01*
X729852Y-232055D01*
X735529Y-217472D01*
Y-234972D01*
G01X742549D02*
Y-217472D01*
X746915D01*
X748662Y-218347D01*
X749972Y-219514D01*
X751064Y-221263D01*
X751937Y-223306D01*
X752155Y-226222D01*
X751937Y-229139D01*
X751064Y-231181D01*
X749972Y-232931D01*
X748662Y-234097D01*
X746915Y-234972D01*
X742549D01*
G01X681735Y-172472D02*
Y-189972D01*
X690469D01*
G01X707532D02*
Y-178306D01*
G01Y-180347D02*
X706659Y-179181D01*
X705348Y-178597D01*
X703820Y-178306D01*
X702292Y-178889D01*
X700982Y-180055D01*
X700108Y-181805D01*
X699672Y-184139D01*
X700108Y-186472D01*
X700982Y-188222D01*
X702292Y-189389D01*
X703820Y-189972D01*
X705348Y-189680D01*
X706659Y-188806D01*
X707532Y-187639D01*
G01X716517Y-195222D02*
X717827Y-195805D01*
X719574Y-195222D01*
X720665Y-194056D01*
X721539Y-192597D01*
X722848Y-187931D01*
X725687Y-178306D01*
G01X718700D02*
X722848Y-187931D01*
G01X735327Y-182097D02*
X742314D01*
X741659Y-180055D01*
X740567Y-178889D01*
X739039Y-178306D01*
X737510Y-178597D01*
X736200Y-179472D01*
X735327Y-181514D01*
X734890Y-183264D01*
Y-185014D01*
X735327Y-186764D01*
X736419Y-188514D01*
X737729Y-189680D01*
X739257Y-189972D01*
X740785Y-189389D01*
X742314Y-187639D01*
G01X753045Y-189972D02*
Y-178306D01*
G01Y-180639D02*
X754137Y-179472D01*
X755229Y-178597D01*
X756757Y-178306D01*
X757848Y-178597D01*
X759159Y-179472D01*
G01X824705Y-218931D02*
X823395Y-218055D01*
X821867Y-217472D01*
X820120D01*
X818155Y-218347D01*
X816627Y-219805D01*
X815535Y-221556D01*
X814662Y-224472D01*
X814443Y-227097D01*
X814880Y-229722D01*
X815535Y-231472D01*
X816845Y-233222D01*
X818374Y-234389D01*
X819902Y-234972D01*
X821430D01*
X822959Y-234389D01*
X824269Y-233514D01*
X825361Y-232348D01*
G01X837402Y-234972D02*
X835655Y-234680D01*
X834127Y-233514D01*
X832817Y-231764D01*
X831943Y-229722D01*
X831507Y-227389D01*
Y-225055D01*
X831943Y-222722D01*
X832817Y-220680D01*
X834127Y-218931D01*
X835655Y-217764D01*
X837402Y-217472D01*
X839148Y-217764D01*
X840677Y-218931D01*
X841987Y-220680D01*
X842861Y-222722D01*
X843297Y-225055D01*
Y-227389D01*
X842861Y-229722D01*
X841987Y-231764D01*
X840677Y-233514D01*
X839148Y-234680D01*
X837402Y-234972D01*
G01X849880D02*
Y-217472D01*
X859924Y-234972D01*
Y-217472D01*
G01X867380Y-234972D02*
Y-217472D01*
X877424Y-234972D01*
Y-217472D01*
G01X887282D02*
X892522D01*
G01X889902D02*
Y-234972D01*
G01X887282D02*
X892522D01*
G01X911769D02*
X903035D01*
Y-217472D01*
X911769D01*
G01X908275Y-225930D02*
X903035D01*
G01X937817Y-234972D02*
X946987Y-217472D01*
G01X937817D02*
X946987Y-234972D01*
G01X955317D02*
Y-217472D01*
G01X964487D02*
Y-234972D01*
G01Y-226222D02*
X955317D01*
G01X823849Y-189972D02*
Y-172472D01*
X828215D01*
X829962Y-173347D01*
X831272Y-174514D01*
X832364Y-176263D01*
X833237Y-178306D01*
X833455Y-181222D01*
X833237Y-184139D01*
X832364Y-186181D01*
X831272Y-187931D01*
X829962Y-189097D01*
X828215Y-189972D01*
X823849D01*
G01X842877Y-182097D02*
X849864D01*
X849209Y-180055D01*
X848117Y-178889D01*
X846589Y-178306D01*
X845060Y-178597D01*
X843750Y-179472D01*
X842877Y-181514D01*
X842440Y-183264D01*
Y-185014D01*
X842877Y-186764D01*
X843969Y-188514D01*
X845279Y-189680D01*
X846807Y-189972D01*
X848335Y-189389D01*
X849864Y-187639D01*
G01X860377Y-187931D02*
X861469Y-189097D01*
X862997Y-189972D01*
X864307D01*
X865617Y-189389D01*
X866490Y-188514D01*
X866927Y-187348D01*
X866709Y-185597D01*
X865835Y-184722D01*
X861905Y-182972D01*
X861032Y-180930D01*
X861469Y-179472D01*
X862342Y-178597D01*
X863652Y-178306D01*
X864962Y-178597D01*
X866272Y-179472D01*
G01X881152Y-178306D02*
Y-189972D01*
G01Y-173639D02*
X880715Y-173347D01*
Y-172764D01*
X881152Y-172472D01*
X881589Y-172764D01*
Y-173347D01*
X881152Y-173639D01*
G01X895595Y-194347D02*
X897124Y-195514D01*
X898870Y-195805D01*
X900398Y-195514D01*
X901709Y-194056D01*
X902582Y-192014D01*
Y-178306D01*
G01Y-180639D02*
X901709Y-179472D01*
X900398Y-178597D01*
X898870Y-178306D01*
X897124Y-178889D01*
X896032Y-180055D01*
X895158Y-182097D01*
X894722Y-184139D01*
X894940Y-185889D01*
X895814Y-187931D01*
X897124Y-189389D01*
X898870Y-189972D01*
X900180Y-189680D01*
X901709Y-188514D01*
X902582Y-187348D01*
G01X912440Y-189972D02*
Y-178306D01*
G01Y-181222D02*
X913314Y-179764D01*
X914624Y-178597D01*
X916370Y-178306D01*
X917898Y-178597D01*
X919209Y-179764D01*
X919864Y-181805D01*
Y-189972D01*
G01X930377Y-182097D02*
X937364D01*
X936709Y-180055D01*
X935617Y-178889D01*
X934089Y-178306D01*
X932560Y-178597D01*
X931250Y-179472D01*
X930377Y-181514D01*
X929940Y-183264D01*
Y-185014D01*
X930377Y-186764D01*
X931469Y-188514D01*
X932779Y-189680D01*
X934307Y-189972D01*
X935835Y-189389D01*
X937364Y-187639D01*
G01X948095Y-189972D02*
Y-178306D01*
G01Y-180639D02*
X949187Y-179472D01*
X950279Y-178597D01*
X951807Y-178306D01*
X952898Y-178597D01*
X954209Y-179472D01*
G01X994852Y-217472D02*
X993105Y-218055D01*
X991795Y-219514D01*
X990922Y-221263D01*
X990267Y-223597D01*
X990049Y-226222D01*
X990267Y-228847D01*
X990922Y-231181D01*
X991795Y-232931D01*
X993105Y-234389D01*
X994852Y-234972D01*
X996598Y-234389D01*
X997909Y-232931D01*
X998782Y-231181D01*
X999437Y-228847D01*
X999655Y-226222D01*
X999437Y-223597D01*
X998782Y-221263D01*
X997909Y-219514D01*
X996598Y-218055D01*
X994852Y-217472D01*
G01X1012352Y-234972D02*
X1013880Y-234680D01*
X1015627Y-233806D01*
X1016719Y-232348D01*
X1017155Y-230305D01*
X1016719Y-228264D01*
X1015409Y-226514D01*
X1013444Y-225639D01*
X1011260D01*
X1009950Y-225055D01*
X1008858Y-223597D01*
X1008422Y-221556D01*
X1009077Y-219514D01*
X1010605Y-218055D01*
X1012352Y-217472D01*
X1014098Y-218055D01*
X1015627Y-219514D01*
X1016282Y-221556D01*
X1015845Y-223597D01*
X1014754Y-225055D01*
X1013444Y-225639D01*
X1011260D01*
X1009295Y-226514D01*
X1007985Y-228264D01*
X1007549Y-230305D01*
X1007985Y-232348D01*
X1009077Y-233806D01*
X1010824Y-234680D01*
X1012352Y-234972D01*
G01X1025922Y-235555D02*
X1033782Y-217472D01*
G01X1043204Y-220389D02*
X1044514Y-218639D01*
X1046042Y-217764D01*
X1047789Y-217472D01*
X1049972Y-218055D01*
X1051500Y-219514D01*
X1051937Y-221263D01*
X1051719Y-223014D01*
X1050845Y-224472D01*
X1046479Y-227389D01*
X1044514Y-229430D01*
X1043204Y-232348D01*
X1042767Y-234972D01*
X1051937D01*
G01X1060049Y-232348D02*
X1061358Y-233806D01*
X1062887Y-234680D01*
X1064852Y-234972D01*
X1066817Y-234389D01*
X1068345Y-233222D01*
X1069437Y-231181D01*
X1069655Y-228847D01*
X1069219Y-226514D01*
X1068127Y-225055D01*
X1066598Y-223889D01*
X1065070Y-223597D01*
X1063542Y-223889D01*
X1061577Y-225055D01*
X1062232Y-217472D01*
X1068127D01*
G01X1078422Y-235555D02*
X1086282Y-217472D01*
G01X1095704Y-220389D02*
X1097014Y-218639D01*
X1098542Y-217764D01*
X1100289Y-217472D01*
X1102472Y-218055D01*
X1104000Y-219514D01*
X1104437Y-221263D01*
X1104219Y-223014D01*
X1103345Y-224472D01*
X1098979Y-227389D01*
X1097014Y-229430D01*
X1095704Y-232348D01*
X1095267Y-234972D01*
X1104437D01*
G01X1117352Y-217472D02*
X1115605Y-218055D01*
X1114295Y-219514D01*
X1113422Y-221263D01*
X1112767Y-223597D01*
X1112549Y-226222D01*
X1112767Y-228847D01*
X1113422Y-231181D01*
X1114295Y-232931D01*
X1115605Y-234389D01*
X1117352Y-234972D01*
X1119098Y-234389D01*
X1120409Y-232931D01*
X1121282Y-231181D01*
X1121937Y-228847D01*
X1122155Y-226222D01*
X1121937Y-223597D01*
X1121282Y-221263D01*
X1120409Y-219514D01*
X1119098Y-218055D01*
X1117352Y-217472D01*
G01X1134852Y-234972D02*
Y-217472D01*
X1132232Y-220972D01*
G01Y-234972D02*
X1137472D01*
G01X1148204Y-227681D02*
X1149732Y-225639D01*
X1151042Y-224472D01*
X1152789Y-223889D01*
X1154317Y-224472D01*
X1155409Y-225639D01*
X1156282Y-227389D01*
X1156500Y-229430D01*
X1156282Y-231181D01*
X1155409Y-232931D01*
X1154098Y-234389D01*
X1152570Y-234972D01*
X1150824Y-234389D01*
X1149295Y-232639D01*
X1148422Y-230014D01*
X1148204Y-227097D01*
X1148640Y-223306D01*
X1149295Y-221263D01*
X1150387Y-219222D01*
X1151915Y-217764D01*
X1153444Y-217472D01*
X1154972Y-218055D01*
X1156064Y-219514D01*
G01X1042549Y-189972D02*
Y-172472D01*
X1046915D01*
X1048662Y-173347D01*
X1049972Y-174514D01*
X1051064Y-176263D01*
X1051937Y-178306D01*
X1052155Y-181222D01*
X1051937Y-184139D01*
X1051064Y-186181D01*
X1049972Y-187931D01*
X1048662Y-189097D01*
X1046915Y-189972D01*
X1042549D01*
G01X1068782D02*
Y-178306D01*
G01Y-180347D02*
X1067909Y-179181D01*
X1066598Y-178597D01*
X1065070Y-178306D01*
X1063542Y-178889D01*
X1062232Y-180055D01*
X1061358Y-181805D01*
X1060922Y-184139D01*
X1061358Y-186472D01*
X1062232Y-188222D01*
X1063542Y-189389D01*
X1065070Y-189972D01*
X1066598Y-189680D01*
X1067909Y-188806D01*
X1068782Y-187639D01*
G01X1082352Y-172472D02*
Y-189972D01*
G01X1079295Y-178306D02*
X1085409D01*
G01X1096577Y-182097D02*
X1103564D01*
X1102909Y-180055D01*
X1101817Y-178889D01*
X1100289Y-178306D01*
X1098760Y-178597D01*
X1097450Y-179472D01*
X1096577Y-181514D01*
X1096140Y-183264D01*
Y-185014D01*
X1096577Y-186764D01*
X1097669Y-188514D01*
X1098979Y-189680D01*
X1100507Y-189972D01*
X1102035Y-189389D01*
X1103564Y-187639D01*
G54D49*
X108040Y59450D03*
X110600D03*
X113160D03*
Y65950D03*
X108040D03*
X125460Y65750D03*
X122900D03*
X120340D03*
Y59250D03*
X125460D03*
G54D58*
X410970Y37500D03*
X407357Y45482D03*
X404023Y61327D03*
X406449Y40438D03*
X448600Y109400D03*
X471500Y209500D03*
G54D59*
X428027Y88710D03*
X445795Y78376D03*
M02*
